(kicad_pcb
	(version 20241229)
	(generator "pcbnew")
	(generator_version "9.0")
	(general
		(thickness 1.61)
		(legacy_teardrops no)
	)
	(paper "A3")
	(title_block
		(title "RDIMM DDR5 Tester")
		(date "2026-05-21")
		(rev "2.2.0")
		(company "Antmicro")
		(comment 9 "footprints 77-81 of 796")
	)
	(layers
		(0 "F.Cu" signal)
		(4 "In1.Cu" power)
		(6 "In2.Cu" mixed)
		(8 "In3.Cu" power)
		(10 "In4.Cu" mixed)
		(12 "In5.Cu" power)
		(14 "In6.Cu" mixed)
		(16 "In7.Cu" power)
		(18 "In8.Cu" power)
		(20 "In9.Cu" mixed)
		(22 "In10.Cu" power)
		(2 "B.Cu" signal)
		(9 "F.Adhes" user "F.Adhesive")
		(11 "B.Adhes" user "B.Adhesive")
		(13 "F.Paste" user)
		(15 "B.Paste" user)
		(5 "F.SilkS" user "F.Silkscreen")
		(7 "B.SilkS" user "B.Silkscreen")
		(1 "F.Mask" user)
		(3 "B.Mask" user)
		(17 "Dwgs.User" user "User.Drawings")
		(19 "Cmts.User" user "User.Comments")
		(21 "Eco1.User" user "User.Eco1")
		(23 "Eco2.User" user "User.Eco2")
		(25 "Edge.Cuts" user)
		(27 "Margin" user)
		(31 "F.CrtYd" user "F.Courtyard")
		(29 "B.CrtYd" user "B.Courtyard")
		(35 "F.Fab" user)
		(33 "B.Fab" user)
	)
	(footprint "antmicro-footprints:R_0402_1005Metric"
		(layer "F.Cu")
		(at 124.681 166.1125 90)
		(descr "Resistor SMD 0402")
		(tags "resistor SMD 0402")
		(property "Reference" "R227"
			(at 0.9125 3.969 90)
			(layer "F.SilkS")
			(effects
				(font
					(size 0.7 0.7)
					(thickness 0.15)
				)
				(justify left bottom)
			)
		)
		(property "Value" "R_64k9_0402"
			(at -1.011843 1.772047 90)
			(layer "F.Fab")
			(effects
				(font
					(size 0.7 0.7)
					(thickness 0.15)
				)
				(justify left bottom)
			)
		)
		(property "Datasheet" "https://www.bourns.com/docs/product-datasheets/cr.pdf"
			(at 0 0 90)
			(layer "F.Fab")
			(hide yes)
			(effects
				(font
					(size 1.27 1.27)
					(thickness 0.15)
				)
			)
		)
		(property "MPN" "CR0402-FX-6492GLF"
			(at 0 0 90)
			(unlocked yes)
			(layer "F.Fab")
			(hide yes)
			(effects
				(font
					(size 1 1)
					(thickness 0.15)
				)
			)
		)
		(property "Manufacturer" "Bourns"
			(at 0 0 90)
			(unlocked yes)
			(layer "F.Fab")
			(hide yes)
			(effects
				(font
					(size 1 1)
					(thickness 0.15)
				)
			)
		)
		(property "License" "Apache-2.0"
			(at 0 0 90)
			(unlocked yes)
			(layer "F.Fab")
			(hide yes)
			(effects
				(font
					(size 1 1)
					(thickness 0.15)
				)
			)
		)
		(property "Author" "Antmicro"
			(at 0 0 90)
			(unlocked yes)
			(layer "F.Fab")
			(hide yes)
			(effects
				(font
					(size 1 1)
					(thickness 0.15)
				)
			)
		)
		(property "Val" "64k9"
			(at 0 0 90)
			(unlocked yes)
			(layer "F.Fab")
			(hide yes)
			(effects
				(font
					(size 1 1)
					(thickness 0.15)
				)
			)
		)
		(property "Tolerance" "1%"
			(at 0 0 90)
			(unlocked yes)
			(layer "F.Fab")
			(hide yes)
			(effects
				(font
					(size 1 1)
					(thickness 0.15)
				)
			)
		)
		(sheetname "/HDMI + SD Card/")
		(sheetfile "hdmi-sd-card.kicad_sch")
		(attr smd exclude_from_bom dnp)
		(fp_rect
			(start -0.925 -0.47)
			(end 0.925 0.47)
			(stroke
				(width 0.05)
				(type default)
			)
			(fill no)
			(layer "F.CrtYd")
		)
		(fp_rect
			(start -0.5 -0.25)
			(end 0.5 0.25)
			(stroke
				(width 0.15)
				(type solid)
			)
			(fill no)
			(layer "F.Fab")
		)
		(fp_text user "${REFERENCE}"
			(at -0.95 3.168 90)
			(layer "F.Fab")
			(effects
				(font
					(size 0.7 0.7)
					(thickness 0.15)
				)
				(justify left bottom)
			)
		)
		(fp_text user "License: Apache-2.0"
			(at -0.95 5.169 90)
			(layer "F.Fab")
			(effects
				(font
					(size 0.7 0.7)
					(thickness 0.15)
				)
				(justify left bottom)
			)
		)
		(fp_text user "Author: Antmicro"
			(at -0.95 4.169 90)
			(layer "F.Fab")
			(effects
				(font
					(size 0.7 0.7)
					(thickness 0.15)
				)
				(justify left bottom)
			)
		)
		(pad "1" smd roundrect
			(at -0.48 0 90)
			(size 0.59 0.64)
			(layers "F.Cu" "F.Mask" "F.Paste")
			(roundrect_rratio 0.25)
			(net 737 "/HDMI + SD Card/EQ_SEL")
			(pintype "passive")
		)
		(pad "2" smd roundrect
			(at 0.48 0 90)
			(size 0.59 0.64)
			(layers "F.Cu" "F.Mask" "F.Paste")
			(roundrect_rratio 0.25)
			(net 151 "+3V3")
			(pintype "passive")
		)
	)
	(footprint "antmicro-footprints:C_0402_1005Metric"
		(layer "F.Cu")
		(at 250.4 120.7 -90)
		(descr "Capacitor SMD 0402")
		(tags "capacitor SMD 0402")
		(property "Reference" "C169"
			(at -1.375501 -0.649 90)
			(layer "F.SilkS")
			(effects
				(font
					(size 0.7 0.7)
					(thickness 0.15)
				)
				(justify right top)
			)
		)
		(property "Value" "C_100n_0402"
			(at -1.022927 2.155213 90)
			(layer "F.Fab")
			(effects
				(font
					(size 0.7 0.7)
					(thickness 0.15)
				)
				(justify right top)
			)
		)
		(property "Datasheet" "https://www.murata.com/products/productdetail?partno=GRM155R61H104KE14%23"
			(at 0 0 90)
			(layer "F.Fab")
			(hide yes)
			(effects
				(font
					(size 1.27 1.27)
					(thickness 0.15)
				)
			)
		)
		(property "Manufacturer" "Murata"
			(at 0 0 270)
			(unlocked yes)
			(layer "F.Fab")
			(hide yes)
			(effects
				(font
					(size 1 1)
					(thickness 0.15)
				)
			)
		)
		(property "MPN" "GRM155R61H104KE14D"
			(at 0 0 270)
			(unlocked yes)
			(layer "F.Fab")
			(hide yes)
			(effects
				(font
					(size 1 1)
					(thickness 0.15)
				)
			)
		)
		(property "Val" "100n"
			(at 0 0 270)
			(unlocked yes)
			(layer "F.Fab")
			(hide yes)
			(effects
				(font
					(size 1 1)
					(thickness 0.15)
				)
			)
		)
		(property "License" "Apache-2.0"
			(at 0 0 270)
			(unlocked yes)
			(layer "F.Fab")
			(hide yes)
			(effects
				(font
					(size 1 1)
					(thickness 0.15)
				)
			)
		)
		(property "Author" "Antmicro"
			(at 0 0 270)
			(unlocked yes)
			(layer "F.Fab")
			(hide yes)
			(effects
				(font
					(size 1 1)
					(thickness 0.15)
				)
			)
		)
		(property "Voltage" "50V"
			(at 0 0 270)
			(unlocked yes)
			(layer "F.Fab")
			(hide yes)
			(effects
				(font
					(size 1 1)
					(thickness 0.15)
				)
			)
		)
		(property "Dielectric" "X5R"
			(at 0 0 270)
			(unlocked yes)
			(layer "F.Fab")
			(hide yes)
			(effects
				(font
					(size 1 1)
					(thickness 0.15)
				)
			)
		)
		(sheetname "/Supply/")
		(sheetfile "supply.kicad_sch")
		(attr smd)
		(fp_rect
			(start -0.925 -0.47)
			(end 0.925 0.47)
			(stroke
				(width 0.05)
				(type default)
			)
			(fill no)
			(layer "F.CrtYd")
		)
		(fp_line
			(start -0.494 0.248)
			(end -0.494 -0.25)
			(stroke
				(width 0.15)
				(type solid)
			)
			(layer "F.Fab")
		)
		(fp_line
			(start 0.504 0.248)
			(end -0.494 0.248)
			(stroke
				(width 0.15)
				(type solid)
			)
			(layer "F.Fab")
		)
		(fp_line
			(start -0.494 -0.25)
			(end 0.504 -0.25)
			(stroke
				(width 0.15)
				(type solid)
			)
			(layer "F.Fab")
		)
		(fp_line
			(start 0.504 -0.25)
			(end 0.504 0.248)
			(stroke
				(width 0.15)
				(type solid)
			)
			(layer "F.Fab")
		)
		(fp_text user "Author: Antmicro"
			(at -0.939 3.399 270)
			(layer "F.Fab")
			(effects
				(font
					(size 0.7 0.7)
					(thickness 0.15)
				)
				(justify left bottom)
			)
		)
		(fp_text user "${REFERENCE}"
			(at -0.939 4.599 270)
			(layer "F.Fab")
			(effects
				(font
					(size 0.7 0.7)
					(thickness 0.15)
				)
				(justify left bottom)
			)
		)
		(fp_text user "License: Apache-2.0"
			(at -0.939 5.799 270)
			(layer "F.Fab")
			(effects
				(font
					(size 0.7 0.7)
					(thickness 0.15)
				)
				(justify left bottom)
			)
		)
		(pad "1" smd roundrect
			(at -0.48 0 270)
			(size 0.59 0.64)
			(layers "F.Cu" "F.Mask" "F.Paste")
			(roundrect_rratio 0.25)
			(net 1 "GND")
			(pintype "passive")
		)
		(pad "2" smd roundrect
			(at 0.48 0 270)
			(size 0.59 0.64)
			(layers "F.Cu" "F.Mask" "F.Paste")
			(roundrect_rratio 0.25)
			(net 325 "/Supply/12V_aux")
			(pintype "passive")
		)
	)
	(footprint "antmicro-footprints:R_0805_2012Metric"
		(layer "F.Cu")
		(at 257.125 165.621 180)
		(property "Reference" "R144"
			(at 5.375 -0.029 180)
			(layer "F.SilkS")
			(effects
				(font
					(size 0.7 0.7)
					(thickness 0.15)
				)
				(justify left bottom)
			)
		)
		(property "Value" "R_0R002_0805"
			(at 0 1.8 180)
			(layer "F.Fab")
			(effects
				(font
					(size 0.7 0.7)
					(thickness 0.15)
				)
				(justify left bottom)
			)
		)
		(property "Datasheet" "https://www2.mouser.com/datasheet/2/447/PYu_PA0100_2512_51_RoHS_2-2604383.pdf"
			(at 0 0 180)
			(layer "F.Fab")
			(hide yes)
			(effects
				(font
					(size 1.27 1.27)
					(thickness 0.15)
				)
			)
		)
		(property "MPN" "PA0805FRE470R002L"
			(at 0 0 180)
			(unlocked yes)
			(layer "F.Fab")
			(hide yes)
			(effects
				(font
					(size 1 1)
					(thickness 0.15)
				)
			)
		)
		(property "Manufacturer" "YAGEO"
			(at 0 0 180)
			(unlocked yes)
			(layer "F.Fab")
			(hide yes)
			(effects
				(font
					(size 1 1)
					(thickness 0.15)
				)
			)
		)
		(property "License" "Apache-2.0"
			(at 0 0 180)
			(unlocked yes)
			(layer "F.Fab")
			(hide yes)
			(effects
				(font
					(size 1 1)
					(thickness 0.15)
				)
			)
		)
		(property "Author" "Antmicro"
			(at 0 0 180)
			(unlocked yes)
			(layer "F.Fab")
			(hide yes)
			(effects
				(font
					(size 1 1)
					(thickness 0.15)
				)
			)
		)
		(property "Val" "0R002"
			(at 0 0 180)
			(unlocked yes)
			(layer "F.Fab")
			(hide yes)
			(effects
				(font
					(size 1 1)
					(thickness 0.15)
				)
			)
		)
		(property "Tolerance" "1%"
			(at 0 0 180)
			(unlocked yes)
			(layer "F.Fab")
			(hide yes)
			(effects
				(font
					(size 1 1)
					(thickness 0.15)
				)
			)
		)
		(sheetname "/Supply/DC-DC AUX, MGT/")
		(sheetfile "dc-dc-aux-mgt.kicad_sch")
		(attr smd)
		(fp_line
			(start -0.3 -0.701)
			(end 0.298 -0.701)
			(stroke
				(width 0.15)
				(type solid)
			)
			(layer "F.SilkS")
		)
		(fp_line
			(start -0.32 0.699)
			(end 0.28 0.699)
			(stroke
				(width 0.15)
				(type solid)
			)
			(layer "F.SilkS")
		)
		(fp_rect
			(start 1.95 -0.9)
			(end -1.95 0.9)
			(stroke
				(width 0.05)
				(type default)
			)
			(fill no)
			(layer "F.CrtYd")
		)
		(fp_line
			(start 0.949 -0.677)
			(end 0.949 0.675)
			(stroke
				(width 0.15)
				(type solid)
			)
			(layer "F.Fab")
		)
		(fp_line
			(start -0.951 0.68)
			(end 0.949 0.68)
			(stroke
				(width 0.15)
				(type solid)
			)
			(layer "F.Fab")
		)
		(fp_line
			(start -0.951 -0.677)
			(end -0.951 0.675)
			(stroke
				(width 0.15)
				(type solid)
			)
			(layer "F.Fab")
		)
		(fp_line
			(start -0.951 -0.682)
			(end 0.949 -0.682)
			(stroke
				(width 0.15)
				(type solid)
			)
			(layer "F.Fab")
		)
		(fp_text user "Author: Antmicro"
			(at -1.9 4.4 180)
			(layer "F.Fab")
			(effects
				(font
					(size 0.7 0.7)
					(thickness 0.15)
				)
				(justify left bottom)
			)
		)
		(fp_text user "${REFERENCE}"
			(at -1.9 3.1 180)
			(layer "F.Fab")
			(effects
				(font
					(size 0.7 0.7)
					(thickness 0.15)
				)
				(justify left bottom)
			)
		)
		(fp_text user "License: Apache-2.0"
			(at -1.9 5.75 180)
			(layer "F.Fab")
			(effects
				(font
					(size 0.7 0.7)
					(thickness 0.15)
				)
				(justify left bottom)
			)
		)
		(pad "1" smd roundrect
			(at -1.1 0 180)
			(size 1.2 1.3)
			(layers "F.Cu" "F.Mask" "F.Paste")
			(roundrect_rratio 0.25)
			(net 47 "/Supply/DC-DC AUX, MGT/MGTAVCC_local")
			(pintype "passive")
		)
		(pad "2" smd roundrect
			(at 1.1 0 180)
			(size 1.2 1.3)
			(layers "F.Cu" "F.Mask" "F.Paste")
			(roundrect_rratio 0.25)
			(net 820 "+0V9_MGTAVCC")
			(pintype "passive")
		)
	)
	(footprint "antmicro-footprints:SW_KMR211NGLFS_SMD"
		(layer "F.Cu")
		(at 260.573 130.551499 -90)
		(property "Reference" "SW5"
			(at 1.1 2.05 90)
			(layer "F.SilkS")
			(hide yes)
			(effects
				(font
					(size 0.7 0.7)
					(thickness 0.15)
				)
				(justify right bottom)
			)
		)
		(property "Value" "SW_KMR211NGLFS_SMD"
			(at 0 2.8 90)
			(layer "F.Fab")
			(effects
				(font
					(size 0.7 0.7)
					(thickness 0.15)
				)
				(justify right bottom)
			)
		)
		(property "Datasheet" "http://www.farnell.com/datasheets/2631211.pdf"
			(at 0 0 270)
			(layer "F.Fab")
			(hide yes)
			(effects
				(font
					(size 1.27 1.27)
					(thickness 0.15)
				)
			)
		)
		(property "MPN" "KMR211NGLFS"
			(at 0 0 270)
			(unlocked yes)
			(layer "F.Fab")
			(hide yes)
			(effects
				(font
					(size 1 1)
					(thickness 0.15)
				)
			)
		)
		(property "Manufacturer" "C&K"
			(at 0 0 270)
			(unlocked yes)
			(layer "F.Fab")
			(hide yes)
			(effects
				(font
					(size 1 1)
					(thickness 0.15)
				)
			)
		)
		(property "Author" "Antmicro"
			(at 0 0 270)
			(unlocked yes)
			(layer "F.Fab")
			(hide yes)
			(effects
				(font
					(size 1 1)
					(thickness 0.15)
				)
			)
		)
		(property "License" "Apache-2.0"
			(at 0 0 270)
			(unlocked yes)
			(layer "F.Fab")
			(hide yes)
			(effects
				(font
					(size 1 1)
					(thickness 0.15)
				)
			)
		)
		(sheetname "/Supply/")
		(sheetfile "supply.kicad_sch")
		(attr smd)
		(fp_line
			(start -2.1 1.601)
			(end -2.1 1.48)
			(stroke
				(width 0.15)
				(type solid)
			)
			(layer "F.SilkS")
		)
		(fp_line
			(start 2.101 1.601)
			(end -2.1 1.601)
			(stroke
				(width 0.15)
				(type solid)
			)
			(layer "F.SilkS")
		)
		(fp_line
			(start 2.101 1.601)
			(end 2.101 1.48)
			(stroke
				(width 0.15)
				(type solid)
			)
			(layer "F.SilkS")
		)
		(fp_line
			(start 2.101 -1.58)
			(end 2.101 -1.459)
			(stroke
				(width 0.15)
				(type solid)
			)
			(layer "F.SilkS")
		)
		(fp_line
			(start -2.1 -1.6)
			(end -2.1 -1.499)
			(stroke
				(width 0.15)
				(type solid)
			)
			(layer "F.SilkS")
		)
		(fp_line
			(start 2.101 -1.6)
			(end -2.1 -1.6)
			(stroke
				(width 0.15)
				(type solid)
			)
			(layer "F.SilkS")
		)
		(fp_rect
			(start 2.751 1.75)
			(end -2.748 -1.749)
			(stroke
				(width 0.05)
				(type solid)
			)
			(fill no)
			(layer "F.CrtYd")
		)
		(fp_line
			(start -2.1 1.601)
			(end 2.101 1.601)
			(stroke
				(width 0.15)
				(type solid)
			)
			(layer "F.Fab")
		)
		(fp_line
			(start 2.101 1.601)
			(end 2.101 -1.6)
			(stroke
				(width 0.15)
				(type solid)
			)
			(layer "F.Fab")
		)
		(fp_line
			(start 0.25 0.802)
			(end -0.248 0.802)
			(stroke
				(width 0.15)
				(type solid)
			)
			(layer "F.Fab")
		)
		(fp_line
			(start -0.248 -0.8)
			(end 0.25 -0.8)
			(stroke
				(width 0.15)
				(type solid)
			)
			(layer "F.Fab")
		)
		(fp_line
			(start -2.1 -1.6)
			(end -2.1 1.601)
			(stroke
				(width 0.15)
				(type solid)
			)
			(layer "F.Fab")
		)
		(fp_line
			(start 2.101 -1.6)
			(end -2.1 -1.6)
			(stroke
				(width 0.15)
				(type solid)
			)
			(layer "F.Fab")
		)
		(fp_arc
			(start -0.248 0.802)
			(mid -1.050001 0.001)
			(end -0.248 -0.8)
			(stroke
				(width 0.15)
				(type solid)
			)
			(layer "F.Fab")
		)
		(fp_arc
			(start 0.25 -0.8)
			(mid 1.051001 0.001)
			(end 0.25 0.802)
			(stroke
				(width 0.15)
				(type solid)
			)
			(layer "F.Fab")
		)
		(fp_text user "${REFERENCE}"
			(at -3 4.25 270)
			(layer "F.Fab")
			(effects
				(font
					(size 0.7 0.7)
					(thickness 0.15)
				)
				(justify left bottom)
			)
		)
		(fp_text user "Author: Antmicro"
			(at -3 5.5 270)
			(layer "F.Fab")
			(effects
				(font
					(size 0.7 0.7)
					(thickness 0.15)
				)
				(justify left bottom)
			)
		)
		(fp_text user "License: Apache-2.0"
			(at -3 6.75 270)
			(layer "F.Fab")
			(effects
				(font
					(size 0.7 0.7)
					(thickness 0.15)
				)
				(justify left bottom)
			)
		)
		(pad "1" smd rect
			(at -2.048 -0.8 90)
			(size 0.9 1)
			(layers "F.Cu" "F.Mask" "F.Paste")
			(net 1 "GND")
			(pinfunction "1")
			(pintype "passive")
		)
		(pad "2" smd rect
			(at 2.05 -0.8 90)
			(size 0.9 1)
			(layers "F.Cu" "F.Mask" "F.Paste")
			(net 1 "GND")
			(pinfunction "2")
			(pintype "passive")
		)
		(pad "3" smd rect
			(at -2.048 0.802 90)
			(size 0.9 1)
			(layers "F.Cu" "F.Mask" "F.Paste")
			(net 189 "/Supply/~{PB_CTRL_IN}")
			(pinfunction "3")
			(pintype "passive")
		)
		(pad "4" smd rect
			(at 2.05 0.802 90)
			(size 0.9 1)
			(layers "F.Cu" "F.Mask" "F.Paste")
			(net 189 "/Supply/~{PB_CTRL_IN}")
			(pinfunction "4")
			(pintype "passive")
		)
	)
	(footprint "antmicro-footprints:R_1206_3216Metric"
		(layer "F.Cu")
		(at 257.124499 162.424 180)
		(property "Reference" "R148"
			(at 2.524499 -0.426 0)
			(layer "F.SilkS")
			(effects
				(font
					(size 0.7 0.7)
					(thickness 0.15)
				)
				(justify right bottom)
			)
		)
		(property "Value" "R_0R01_1206"
			(at -2.422356 2.103591 0)
			(layer "F.Fab")
			(effects
				(font
					(size 0.7 0.7)
					(thickness 0.15)
				)
				(justify right bottom)
			)
		)
		(property "Datasheet" "https://www.yageo.com/upload/media/product/productsearch/datasheet/rchip/PYu-RL_Group_521_RoHS_L_2.pdf"
			(at 0 0 180)
			(layer "F.Fab")
			(hide yes)
			(effects
				(font
					(size 1.27 1.27)
					(thickness 0.15)
				)
			)
		)
		(property "Manufacturer" "YAGEO"
			(at 0 0 180)
			(unlocked yes)
			(layer "F.Fab")
			(hide yes)
			(effects
				(font
					(size 1 1)
					(thickness 0.15)
				)
			)
		)
		(property "MPN" "RL1206FR-7W0R01L"
			(at 0 0 180)
			(unlocked yes)
			(layer "F.Fab")
			(hide yes)
			(effects
				(font
					(size 1 1)
					(thickness 0.15)
				)
			)
		)
		(property "Val" "0R01"
			(at 0 0 180)
			(unlocked yes)
			(layer "F.Fab")
			(hide yes)
			(effects
				(font
					(size 1 1)
					(thickness 0.15)
				)
			)
		)
		(property "License" "Apache-2.0"
			(at 0 0 180)
			(unlocked yes)
			(layer "F.Fab")
			(hide yes)
			(effects
				(font
					(size 1 1)
					(thickness 0.15)
				)
			)
		)
		(property "Author" "Antmicro"
			(at 0 0 180)
			(unlocked yes)
			(layer "F.Fab")
			(hide yes)
			(effects
				(font
					(size 1 1)
					(thickness 0.15)
				)
			)
		)
		(property "Tolerance" "1%"
			(at 0 0 180)
			(unlocked yes)
			(layer "F.Fab")
			(hide yes)
			(effects
				(font
					(size 1 1)
					(thickness 0.15)
				)
			)
		)
		(sheetname "/Supply/DC-DC IO/")
		(sheetfile "dc-dc-io.kicad_sch")
		(attr smd)
		(fp_line
			(start 0.8 0.901)
			(end -0.8 0.901)
			(stroke
				(width 0.15)
				(type solid)
			)
			(layer "F.SilkS")
		)
		(fp_line
			(start 0.8 -0.899)
			(end -0.8 -0.899)
			(stroke
				(width 0.15)
				(type solid)
			)
			(layer "F.SilkS")
		)
		(fp_rect
			(start -2.325 -1.15)
			(end 2.325 1.15)
			(stroke
				(width 0.05)
				(type default)
			)
			(fill no)
			(layer "F.CrtYd")
		)
		(fp_line
			(start 1.6 -0.802)
			(end 1.6 0.8)
			(stroke
				(width 0.15)
				(type solid)
			)
			(layer "F.Fab")
		)
		(fp_line
			(start -1.601 0.8)
			(end 1.6 0.8)
			(stroke
				(width 0.15)
				(type solid)
			)
			(layer "F.Fab")
		)
		(fp_line
			(start -1.601 -0.802)
			(end 1.6 -0.802)
			(stroke
				(width 0.15)
				(type solid)
			)
			(layer "F.Fab")
		)
		(fp_line
			(start -1.601 -0.802)
			(end -1.601 0.8)
			(stroke
				(width 0.15)
				(type solid)
			)
			(layer "F.Fab")
		)
		(fp_text user "${REFERENCE}"
			(at -2.401 3.5 180)
			(layer "F.Fab")
			(effects
				(font
					(size 0.7 0.7)
					(thickness 0.15)
				)
				(justify left bottom)
			)
		)
		(fp_text user "License: Apache-2.0"
			(at -2.401 6.3 180)
			(layer "F.Fab")
			(effects
				(font
					(size 0.7 0.7)
					(thickness 0.15)
				)
				(justify left bottom)
			)
		)
		(fp_text user "Author: Antmicro"
			(at -2.401 4.899 180)
			(layer "F.Fab")
			(effects
				(font
					(size 0.7 0.7)
					(thickness 0.15)
				)
				(justify left bottom)
			)
		)
		(pad "1" smd roundrect
			(at -1.5 0.001 180)
			(size 1.15 1.8)
			(layers "F.Cu" "F.Mask" "F.Paste")
			(roundrect_rratio 0.25)
			(net 159 "/Supply/DC-DC IO/1V2_local")
			(pintype "passive")
		)
		(pad "2" smd roundrect
			(at 1.5 0.001 180)
			(size 1.15 1.8)
			(layers "F.Cu" "F.Mask" "F.Paste")
			(roundrect_rratio 0.25)
			(net 150 "+1V2")
			(pintype "passive")
		)
	)
)
